# T6G (Grand Teton) — schematic parts with pin connectivity, parts 8156–8195 of 8303; source: Cadence DE-HDL packaged netlist (pstxprt.dat, pstxnet.dat, pstchip.dat)

U181  PCA9539RPW  IC  pkg TSSOP24XB  page 245
  1  INT  BI  = PU_U181_INT
  2  A1  IN  = TCA9539_0_ADD1
  3  RESET  BI  = PU_RST_SMB_U181_N
  4  IO0_0  BI  = RST_USB_HUB_N
  5  IO0_1  BI  = RST_SWB_BIC_N
  6  IO0_2  BI  = TP_TCA9539_0_P0_2
  7  IO0_3  BI  = TP_TCA9539_0_P0_3
  8  IO0_4  BI  = PRSNT_SWB_ISO_R1_N
  9  IO0_5  BI  = GPU_PRSNT_N_ISO_R1
  10  IO0_6  BI  = PRSNT_CABLE_GPU_B3_ISO_R1_N
  11  IO0_7  BI  = PRSNT_CABLE_SWB_B2_ISO_R_N
  12  VSS  POWER  = GND
  13  IO1_0  BI  = PRSNT_CABLE_GPU_A2_ISO_R1_N
  14  IO1_1  BI  = PRSNT_CABLE_SWB_B1_ISO_R_N
  15  IO1_2  BI  = GPU_BASE_ID0_R
  16  IO1_3  BI  = GPU_BASE_ID1_R
  17  IO1_4  BI  = GPU_PEX_STRAP0_R
  18  IO1_5  BI  = GPU_PEX_STRAP1_R
  19  IO1_6  BI  = PRSNT_CABLE_GPU_A1_ISO_R1_N
  20  IO1_7  BI  = PRSNT_CABLE_GPU_A3_ISO_R_N
  21  A0  IN  = TCA9539_0_ADD0
  22  SCL  BI  = SMB_IOEXP_3V3AUX_SCL_R1
  23  SDA  BI  = SMB_IOEXP_3V3AUX_SDA_R1
  24  VDD  POWER  = P3V3_AUX

U190  MOSFET_NCH_GDS_ESD_PROTECTED  2N7002K IC  pkg SOT23_GDSXC  page 240
  D  D  BI  = FM_PDB_BUF_EN_R1
  G  G  IN  = FM_PDB_BUF_EN_R1_N
  S  S  BI  = GND

U192  LTC4307CMS8  IC  pkg MSOP8  page 240
  1  ENABLE  IN  = MB_PDB_SMB9_R_EN
  2  SCL_OUT  BI  = SMB_FAN_3V3AUX_BUF_SCL
  3  SCL_IN  BI  = SMB_FAN_3V3AUX_R_SCL
  4  GND  POWER  = GND
  5  READY  OUT  = NC
  6  SDA_IN  BI  = SMB_FAN_3V3AUX_R_SDA
  7  SDA_OUT  BI  = SMB_FAN_3V3AUX_BUF_SDA
  8  VCC  POWER  = P3V3_AUX

U193  MAX11617EEET  MAX11617EEE+T EMPTY  pkg QSOP16_0-635_4-9X3-89  page 257
  1  \ain11||ref\  BI  = MAX11617_VREF_R
  2  AIN10  BI  = GND
  3  AIN9  BI  = GND
  4  AIN8  BI  = GND
  5  AIN0  BI  = P12V_AUX_ADC_MAM
  6  AIN1  BI  = P12V_OCP_SFF_ISENSE_MAM
  7  AIN2  BI  = P12V_OCP_V3_2_ISENSE_MAM
  8  AIN3  BI  = P5V_ADC_MAM
  9  AIN4  BI  = P3V3_ADC_MAM
  10  AIN5  BI  = P3V3_AUX_ADC_MAM
  11  AIN6  BI  = P3V3_PDB_AUX_ADC_MAM
  12  AIN7  BI  = P12V_E1S_0_ISENSE_MAM
  13  SCL  BI  = SMB_SEN_MAM_3V3AUX_SCL
  14  SDA  BI  = SMB_SEN_MAM_3V3AUX_SDA
  15  GND  POWER  = GND
  16  VDD  POWER  = P3V3_MAX11617_VDD

U194  LTC4307CMS8  IC  pkg MSOP8  page 248
  1  ENABLE  IN  = SMB_BMC_GPU_EN_R1
  2  SCL_OUT  BI  = SMB_1_BMC_GPU_BUF_R_SCL
  3  SCL_IN  BI  = SMB_1_BMC_GPU_R_SCL
  4  GND  POWER  = GND
  5  READY  OUT  = NC
  6  SDA_IN  BI  = SMB_1_BMC_GPU_R_SDA
  7  SDA_OUT  BI  = SMB_1_BMC_GPU_BUF_R_SDA
  8  VCC  POWER  = P3V3_AUX

U195  74LVC2G17GW  IC  pkg SOT363  page 130
  1  A0  IN  = BMC_MONITER_R
  2  GND  POWER  = GND
  3  A1  IN  = RST_SWB_BIC_R_N
  4  B1  OUT  = RST_SWB_BIC_BUF_R_N
  5  VCC  POWER  = P3V3_AUX
  6  B0  OUT  = BMC_MONITER_BUF_R

U196  74LVC2G17GW  IC  pkg SOT363  page 130
  1  A0  IN  = FM_GPU_PWR_EN_R
  2  GND  POWER  = GND
  3  A1  IN  = GPU_FPGA_RST_R_N
  4  B1  OUT  = GPU_FPGA_RST_R1_BUF_N
  5  VCC  POWER  = P3V3_AUX
  6  B0  OUT  = FM_GPU_PWR_EN_R1

U200  LTC4307CMS8  IC  pkg MSOP8  page 248
  1  ENABLE  IN  = SMB_BMC_GPU_EN_R3
  2  SCL_OUT  BI  = SMB_2_BMC_GPU_BUF_R_SCL
  3  SCL_IN  BI  = SMB_2_BMC_GPU_R_SCL
  4  GND  POWER  = GND
  5  READY  OUT  = NC
  6  SDA_IN  BI  = SMB_2_BMC_GPU_R_SDA
  7  SDA_OUT  BI  = SMB_2_BMC_GPU_BUF_R_SDA
  8  VCC  POWER  = P3V3_AUX

U204  74LVC1G126SE7  74LVC1G126SE-7 IC  pkg SOT353_0-65_2X1-25  page 130
  1  OE  IN  = FM_UART_EN
  2  A  IN  = UART_BMC_BIC_R_RX
  3  GND  POWER  = GND
  4  Y  OUT  = UART_BMC_BIC_R_BUF_RX
  5  VCC  POWER  = P3V3_AUX

U206  LT6700CS61TRPBF  LT6700CS6-1#TRPBF EMPTY  pkg TSOT23-6_0-95_2-9X1-625  page 268
  1  OUTA  OUT  = FM_UV_ADR_TRIGGER_N
  2  GND  POWER  = GND
  3  \ina+\  IN  = A_P12V_STBY_ADR_TRIGGER
  4  \inb-\  IN  = A_P12V_STBY_FP_TRIGGER
  5  VS  POWER  = U206_VS
  6  OUTB  OUT  = A_P12V_STBY_FPH_GATE

U207  74LVC1G17GW  IC  pkg TSSOP5  page 139
  1  NC  TRI  = NC
  2  A  IN  = RST_PERST_OCP_V3_2_BUF_N
  3  GND  POWER  = GND
  4  Y  OCA  = RST_PERST_OCP_V3_2_BUF2_N
  5  VCC  POWER  = P3V3_AUX

U211  74LVC2G07DW7  74LVC2G07DW-7 IC  pkg SOT363_0-65_2X1-25XC  page 134
  1  \1a\  IN  = OCP_SFF_PRSNT0_R_N
  2  GND  POWER  = GND
  3  \2a\  IN  = OCP_SFF_PRSNT1_R_N
  4  \2y\  OUT  = HP_LVC3_OCP_V3_1_PRSNT2_N_R
  5  VCC  POWER  = P3V3_AUX
  6  \1y\  OUT  = HP_LVC3_OCP_V3_1_PRSNT2_N_R

U212  74LV4052PW  IC  pkg TSSOP16_0-65_5X4-4XH  page 171
  1  \2y0\  BI  = TP_JTAG_SCM_SLOT3_R_TDO
  2  \2y2\  BI  = JTAG_SCM_PLD_R_TDO
  3  \2z\  BI  = JTAG_SCM_TDO
  4  \2y3\  BI  = JTAG_SCM_PLD_R_TDO
  5  \2y1\  BI  = JTAG_SCM_MUX_R_TDO
  6  E_N  BI  = U212_EN_N
  7  VEE  POWER  = GND
  8  GND  POWER  = GND
  9  S1  BI  = SCM_JTAG_MUX_S1
  10  S0  BI  = SCM_JTAG_MUX_S0_R2
  11  \1y3\  BI  = JTAG_SCM_PLD_R_TDI
  12  \1y0\  BI  = TP_JTAG_SCM_SLOT3_R_TDI
  13  \1z\  BI  = JTAG_SCM_TDI
  14  \1y1\  BI  = JTAG_SCM_MUX_R_TDI
  15  \1y2\  BI  = JTAG_SCM_PLD_R_TDI
  16  VCC  POWER  = P3V3_AUX

U213  IML3112Y2B000NCG8  IML3112-Y2B000NCG8 EMPTY  pkg DFN8_TH_0-5_2X3XC  page 161
  1  LSDA_0  BI  = SMB_APML_CPU0_R_SDA
  2  HSDA  BI  = SMB_CPU0_CPU1_APML_MUX1_SDA
  3  HSCL  IN  = SMB_CPU0_CPU1_APML_MUX1_SCL
  4  LSCL_0  OUT  = SMB_APML_CPU0_R_SCL
  5  VDD  POWER  = PVDD18_S5_P0
  6  LSCL_1  OUT  = SMB_APML_CPU1_R_SCL
  7  VIO  POWER  = I3C_MUX_CPU0_VIO
  8  \lsda_1||hsa\  BI  = SMB_APML_CPU1_R_SDA
  9  TH_GND  POWER  = GND

U217  74LVC1G126SE7  74LVC1G126SE-7 IC  pkg SOT353_0-65_2X1-25  page 139
  1  OE  IN  = PU_OCP_V3_2_WAKE_OE
  2  A  IN  = IRQ_LVC3_OCP_V3_2_WAKE_N
  3  GND  POWER  = GND
  4  Y  OUT  = OCP_V3_2_WAKE_BUFF_N
  5  VCC  POWER  = P3V3_AUX

U218  74LVC1G07GV  IC  pkg SC-74A_2-9X1-5  page 139
  1  NC1  TRI  = NC_U218_NC1
  2  A  IN  = FM_SYS_THROTTLE_N
  3  GND  POWER  = GND
  4  Y  OCA  = OCP_V3_2_PWRBRK_BUFF_N
  5  VCC  POWER  = P3V3_AUX

U219  74LVC1G07GV  IC  pkg SC-74A_2-9X1-5  page 139
  1  NC1  TRI  = NC_U219_NC1
  2  A  IN  = OCP_V3_2_WAKE_BUFF_R_N
  3  GND  POWER  = GND
  4  Y  OCA  = IRQ_LVC3_V3_2_WAKE_BUF_N
  5  VCC  POWER  = P3V3_AUX

U222  74CBTLV3126PW  IC  pkg TSSOP14  page 138
  1  \1oe\  IN  = FB_BMC_ISOLATE1
  2  \1a\  POWER  = NCSI_BMC_RXD1_R1
  3  \1b\  BI  = NCSI_OCP_V3_2_RXD1
  4  \2oe\  OUT  = FB_BMC_ISOLATE1
  5  \2a\  BI  = NCSI_BMC_RXD0_R1
  6  \2b\  BI  = NCSI_OCP_V3_2_RXD0
  7  GND  POWER  = GND
  8  \3b\  BI  = NCSI_OCP_V3_2_CRS_DV
  9  \3a\  BI  = NCSI_BMC_CRS_DV_R1
  10  \3oe\  BI  = FB_BMC_ISOLATE1
  11  \4b\  BI  = OCP_V3_2_ISO1_RBT_ARB_IN
  12  \4a\  BI  = OCP_V3_2_RBT_ARB_IN_R
  13  \4oe\  BI  = FB_BMC_ISOLATE1
  14  VCC  BI  = P3V3_AUX

U223  74CBTLV3126PW  IC  pkg TSSOP14  page 138
  1  \1oe\  IN  = FB_BMC_ISOLATE1
  2  \1a\  POWER  = NCSI_BMC_TXD1_R1
  3  \1b\  BI  = NCSI_OCP_V3_2_TXD1
  4  \2oe\  OUT  = FB_BMC_ISOLATE1
  5  \2a\  BI  = NCSI_BMC_TXD0_R1
  6  \2b\  BI  = NCSI_OCP_V3_2_TXD0
  7  GND  POWER  = GND
  8  \3b\  BI  = NCSI_OCP_V3_2_TX_EN
  9  \3a\  BI  = NCSI_BMC_TX_EN_R1
  10  \3oe\  BI  = FB_BMC_ISOLATE1
  11  \4b\  BI  = OCP_V3_2_ISO2_RBT_ARB_OUT
  12  \4a\  BI  = OCP_V3_2_RBT_ARB_OUT
  13  \4oe\  BI  = FB_BMC_ISOLATE1
  14  VCC  BI  = P3V3_AUX

U224  74LVC1G126SE7  74LVC1G126SE-7 IC  pkg SOT353_0-65_2X1-25  page 132
  1  OE  IN  = OCP_SFF_AUX_PWR_EN_R2
  2  A  IN  = RST_SMB_SWITCH_N
  3  GND  POWER  = GND
  4  Y  OUT  = RST_HP_OCP_SFF_R_N
  5  VCC  POWER  = P3V3_AUX

U225  74LVC1G126SE7  74LVC1G126SE-7 IC  pkg SOT353_0-65_2X1-25  page 139
  1  OE  IN  = OCP_V3_2_AUX_PWR_EN_R3
  2  A  IN  = RST_SMB_SWITCH_N
  3  GND  POWER  = GND
  4  Y  OUT  = RST_HP_OCP_V3_2_R_N
  5  VCC  POWER  = P3V3_AUX

U235  PCA9617ADP  IC  pkg TSSOP8_3XB  page 247
  1  VCCA  POWER  = P3V3_AUX
  2  SCLA  BI  = SMB_OCP_V3_2_3V3AUX_SCL
  3  SDAA  BI  = SMB_OCP_V3_2_3V3AUX_SDA
  4  GND  POWER  = GND
  5  EN  IN  = HP_LVC3_OCP_V3_2_R_EN
  6  SDAB  BI  = SMB_OCP_V3_2_3V3AUX_BUF_SDA
  7  SCLB  BI  = SMB_OCP_V3_2_3V3AUX_BUF_SCL
  8  VCCB  POWER  = P3V3_OCP_V3_2

U236  PCA9617ADP  IC  pkg TSSOP8_3XB  page 247
  1  VCCA  POWER  = P3V3_AUX
  2  SCLA  BI  = SMB_OCP_SFF_3V3AUX_SCL
  3  SDAA  BI  = SMB_OCP_SFF_3V3AUX_SDA
  4  GND  POWER  = GND
  5  EN  IN  = HP_LVC3_OCP_V3_1_R_EN
  6  SDAB  BI  = SMB_OCP_SFF_3V3AUX_BUF_SDA
  7  SCLB  BI  = SMB_OCP_SFF_3V3AUX_BUF_SCL
  8  VCCB  POWER  = P3V3_OCP_SFF

U237  PI3EQX12902AZLEX  IC  pkg TQFN30_TH_0-4_4-5X2-5  page 111
  1  VDD1  POWER  = P3V3_AUX
  2  AIP  IN  = P2E_MB_BMC_TX_C_R1_DP<0>
  3  AIN  IN  = P2E_MB_BMC_TX_C_R1_DN<0>
  4  GND1  POWER  = GND
  5  \test#\  IN  = PU_TEST
  6  GND2  POWER  = GND
  7  GND3  POWER  = GND
  8  BON  OUT  = P2E_MB_BMC_RX_BUF_C_DN<0>
  9  BOP  OUT  = P2E_MB_BMC_RX_BUF_C_DP<0>
  10  VDD2  POWER  = P3V3_AUX
  11  \en#\  IN  = FM_P2E_EN_N
  12  SWB  IN  = FM_P2E_SWB
  13  GND4  POWER  = GND
  14  FGB  IN  = FM_P2E_FGB
  15  EQB1  IN  = FM_P2E_EQB1
  16  VDD3  POWER  = P3V3_AUX
  17  BIP  IN  = P2E_MB_BMC_RX_R1_DP<0>
  18  BIN  IN  = P2E_MB_BMC_RX_R1_DN<0>
  19  GND5  POWER  = GND
  20  EQB0  IN  = FM_P2E_EQB0
  21  EQA0  IN  = FM_P2E_EQA0
  22  GND6  POWER  = GND
  23  AON  OUT  = P2E_MB_BMC_TX_BUF_DN<0>
  24  AOP  OUT  = P2E_MB_BMC_TX_BUF_DP<0>
  25  VDD4  POWER  = P3V3_AUX
  26  EQA1  IN  = FM_P2E_EQA1
  27  FGA  IN  = FM_P2E_FGA
  28  GND7  POWER  = GND
  29  SWA  IN  = FM_P2E_SWA
  30  MODE  IN  = FM_P2E_MODE
  TH  GND_TH  POWER  = GND

U239  74LVC1G126SE7  74LVC1G126SE-7 IC  pkg SOT353_0-65_2X1-25  page 144
  1  OE  IN  = PU_BUFFER_HDD_ACTIVITY
  2  A  IN  = LED_HDD_ACTIVITY_N
  3  GND  POWER  = GND
  4  Y  OUT  = LED_HDD_ACTIVITY_B_N
  5  VCC  POWER  = P3V3_AUX

U240  74LVC2G08DP  EMPTY  pkg TSSOP8_0-65_3X3  page 143
  1  \1a\  IN  = OCP_SFF_PRSNT0_R_N
  2  \1b\  IN  = OCP_SFF_PRSNT1_R_N
  3  \2y\  OUT  = OCP_SFF_PRSNT23_R_N
  4  GND  POWER  = GND
  5  \2a\  IN  = OCP_SFF_PRSNT2_R_N
  6  \2b\  IN  = OCP_SFF_PRSNT3_R_N
  7  \1y\  OUT  = OCP_SFF_PRSNT01_R_N
  8  VCC  POWER  = P3V3_AUX

U241  74LVC2G08DP  EMPTY  pkg TSSOP8_0-65_3X3  page 143
  1  \1a\  IN  = OCP_V3_2_PRSNT0_R_N
  2  \1b\  IN  = OCP_V3_2_PRSNT1_R_N
  3  \2y\  OUT  = OCP_V3_2_PRSNT23_R_N
  4  GND  POWER  = GND
  5  \2a\  IN  = OCP_V3_2_PRSNT2_R_N
  6  \2b\  IN  = OCP_V3_2_PRSNT3_R_N
  7  \1y\  OUT  = OCP_V3_2_PRSNT01_R_N
  8  VCC  POWER  = P3V3_AUX

U242  74LVC2G08DP  EMPTY  pkg TSSOP8_0-65_3X3  page 143
  1  \1a\  IN  = OCP_SFF_PRSNT01_R1_N
  2  \1b\  IN  = OCP_SFF_PRSNT23_R1_N
  3  \2y\  OUT  = OCP_V3_2_PRSNT_ALL_R_N
  4  GND  POWER  = GND
  5  \2a\  IN  = OCP_V3_2_PRSNT01_R1_N
  6  \2b\  IN  = OCP_V3_2_PRSNT23_R1_N
  7  \1y\  OUT  = OCP_SFF_PRSNT_ALL_R_N
  8  VCC  POWER  = P3V3_AUX

U243  NC7SB3157  NC7SB3157P6X EMPTY  pkg SMLF  page 143
  1  B1  BI  = OCP_SFF_NOT_PRSNT_RBT_ARB_IN
  2  GND  POWER  = GND
  3  B0  BI  = OCP_SFF_RBT_ARB_OUT
  4  A  BI  = OCP_SFF_RBT_ARB_IN_MUX2
  5  VCC  POWER  = P3V3_AUX
  6  S  IN  = OCP_SFF_PRSNT_ALL_R1_N

U244  NC7SB3157  NC7SB3157P6X EMPTY  pkg SMLF  page 143
  1  B1  BI  = OCP_SFF_NOT_PRSNT_RBT_ARB_IN
  2  GND  POWER  = GND
  3  B0  BI  = OCP_SFF_RBT_ARB_IN
  4  A  BI  = OCP_SFF_RBT_ARB_IN_MUX1_R
  5  VCC  POWER  = P3V3_AUX
  6  S  IN  = OCP_SFF_PRSNT_ALL_R3_N

U245  NC7SB3157  NC7SB3157P6X EMPTY  pkg SMLF  page 143
  1  B1  BI  = OCP_V3_2_NOT_PRSNT_RBT_ARB_IN
  2  GND  POWER  = GND
  3  B0  BI  = OCP_V3_2_RBT_ARB_IN
  4  A  BI  = OCP_SFF_RBT_ARB_IN_MUX2_R
  5  VCC  POWER  = P3V3_AUX
  6  S  IN  = OCP_V3_2_PRSNT_ALL_R3_N

U246  NC7SB3157  NC7SB3157P6X EMPTY  pkg SMLF  page 143
  1  B1  BI  = OCP_V3_2_NOT_PRSNT_RBT_ARB_IN
  2  GND  POWER  = GND
  3  B0  BI  = OCP_V3_2_RBT_ARB_OUT
  4  A  BI  = OCP_SFF_RBT_ARB_IN_MUX1
  5  VCC  POWER  = P3V3_AUX
  6  S  IN  = OCP_V3_2_PRSNT_ALL_R1_N

U247  9FGL0251DKILFT  IC  pkg VFQFPN24_TH_0-5_4X4XI  page 233
  1  \xin||clkin_25\  IN  = CLK_GEN2_XTAL_IN
  2  X2  OUT  = CLK_GEN2_XTAL_OUT
  3  \vddxtal3.3\  POWER  = VFG3P3_CLK_GEN
  4  \vsadr||ref3.3\  BI  = CLK_GEN2_SMB_SADR
  5  GNDREF  POWER  = GND
  6  GNDDIG  POWER  = GND
  7  \vdddig3.3\  POWER  = VFG3P3_CLK_GEN
  8  \sclk_3.3\  IN  = SMB_HOST_CLK_GEN2_3V3AUX_SCL
  9  \sdata_3.3\  BI  = SMB_HOST_CLK_GEN2_3V3AUX_SDA
  10  GND_10  POWER  = GND
  11  \vdd3.3_11\  POWER  = VFG3P3_CLK_GEN
  12  \voe0#\  IN  = CLK_GEN2_BMC_RC_OE_R3_N
  13  DIF0  OUT  = CLK_100M_BMC_RC_DP_R
  14  \dif0#\  OUT  = CLK_100M_BMC_RC_DN_R
  15  GNDA  POWER  = GND
  16  \vdda3.3\  POWER  = VFG_3P3A_CLK_GEN
  17  DIF1  OUT  = CLK_100M_GPU_FPGA_DP_R
  18  \dif1#\  OUT  = CLK_100M_GPU_FPGA_DN_R
  19  \voe1#\  IN  = CLK_GEN2_GPU_OE_N
  20  \vdd3.3_20\  POWER  = VFG3P3_CLK_GEN
  21  GND_21  POWER  = GND
  22  \^ckpwrgd_pd#\  IN  = P3V3_PWRGD_CLKGEN
  23  \^vss_en_tri\  IN  = FG_SS_EN
  24  GNDXTAL  POWER  = GND
  25  TH_GND  POWER  = GND

U248  74LVC1G32GW  IC  pkg SMLF  page 233
  1  I0  IN  = GPU_FPGA_READY_R_N
  2  I1  IN  = CLK_GEN2_GPU_FPGA_OE_R2_N
  3  GND  POWER  = GND
  4  O  OUT  = CLK_GEN2_GPU_FPGA_OE_OR_N
  5  VCC  POWER  = P3V3_AUX

U252  74LVC2G17GW  IC  pkg SOT363  page 128
  1  A0  IN  = RST_PERST_CPU1_SWB_R_N
  2  GND  POWER  = GND
  3  A1  IN  = RST_PERST_CPU1_SWB_1_R_N
  4  B1  OUT  = RST_PERST_2_SWB_BUF_R_N
  5  VCC  POWER  = P3V3_AUX
  6  B0  OUT  = RST_PERST_0_SWB_BUF_R_N

U253  74LVC2G17GW  IC  pkg SOT363  page 128
  1  A0  IN  = GPU_FPGA_BOOT_EN
  2  GND  POWER  = GND
  3  A1  IN  = GPU_BASE_STBY_EN
  4  B1  OUT  = GPU_BASE_STBY_EN_BUF_R
  5  VCC  POWER  = P3V3_AUX
  6  B0  OUT  = GPU_FPGA_BOOT_EN_BUF_R

U255  74LVC2G07DW7  74LVC2G07DW-7 IC  pkg SOT363_0-65_2X1-25XC  page 129
  1  \1a\  IN  = GPU_NVS_PWR_BRAKE_N
  2  GND  POWER  = GND
  3  \2a\  IN  = GPU_FPGA_EROT_RST_N
  4  \2y\  OUT  = GPU_FPGA_EROT_RST_BUF_R_N
  5  VCC  POWER  = P3V3_AUX
  6  \1y\  OUT  = GPU_NVS_PWR_BRAKE_N_R

U256  74LVC2G17GW  IC  pkg SOT363  page 128
  1  A0  IN  = RST_PERST_CPU0_SWB_R_N
  2  GND  POWER  = GND
  3  A1  IN  = FM_SWB_PWR_EN_R
  4  B1  OUT  = FM_SWB_PWR_EN_R1_BUF
  5  VCC  POWER  = P3V3_AUX
  6  B0  OUT  = RST_PERST_1_SWB_BUF_R_N

U257  74LVC2G07DW7  74LVC2G07DW-7 IC  pkg SOT363_0-65_2X1-25XC  page 129
  1  \1a\  IN  = GPU_FPGA_EROT_RECOV_N
  2  GND  POWER  = GND
  3  \2a\  IN  = GND
  4  \2y\  OUT  = NC_U257_2Y
  5  VCC  POWER  = P3V3_AUX
  6  \1y\  OUT  = GPU_FPGA_EROT_RECOV_BUF_R_N

U259  SN74LVC2G07DCKR  IC  pkg SMLF  page 144
  1  \1a\  IN  = M2_SSD0_CLKREQ_EN_N
  2  GND  POWER  = GND
  3  \2a\  IN  = RST_PERST_M2_0_N
  4  \2y\  OUT  = RST_PERST_BUF_M2_0_N
  5  VCC  POWER  = P3V3_AUX
  6  \1y\  OUT  = HDD_ACTIVITY_BUF
